(kicad_pcb
	(version 20260206)
	(generator "pcbnew")
	(generator_version "10.0")
	(general
		(thickness 1.6)
		(legacy_teardrops no)
	)
	(paper "A4")
	(title_block
		(title "03242023_DA0F0TMBIJ0_F0T_Motherboard_J_brd_V01_OCP.brd")
		(comment 1 "Grand Teton / footprints 1185-1186 of 6105")
	)
	(layers
		(0 "F.Cu" signal "TOP")
		(4 "In1.Cu" signal "GND")
		(6 "In2.Cu" signal "IN1")
		(8 "In3.Cu" signal "GND1")
		(10 "In4.Cu" signal "IN2")
		(12 "In5.Cu" signal "GND2")
		(14 "In6.Cu" signal "IN3")
		(16 "In7.Cu" signal "GND3")
		(18 "In8.Cu" signal "VCC")
		(20 "In9.Cu" signal "VCC1")
		(22 "In10.Cu" signal "GND4")
		(24 "In11.Cu" signal "IN4")
		(26 "In12.Cu" signal "GND5")
		(28 "In13.Cu" signal "IN5")
		(30 "In14.Cu" signal "GND6")
		(32 "In15.Cu" signal "IN6")
		(34 "In16.Cu" signal "GND7")
		(2 "B.Cu" signal "BOTTOM")
		(9 "F.Adhes" user "F.Adhesive")
		(11 "B.Adhes" user "B.Adhesive")
		(13 "F.Paste" user "Package Geometry/Pastemask Top")
		(15 "B.Paste" user "Package Geometry/Pastemask Bottom")
		(5 "F.SilkS" user "Ref Des/Silkscreen Top")
		(7 "B.SilkS" user "Ref Des/Silkscreen Bottom")
		(1 "F.Mask" user "Board Geometry/Soldermask Top")
		(3 "B.Mask" user "Board Geometry/Soldermask Bottom")
		(17 "Dwgs.User" user "User.Drawings")
		(19 "Cmts.User" user "User.Comments")
		(21 "Eco1.User" user "User.Eco1")
		(23 "Eco2.User" user "User.Eco2")
		(25 "Edge.Cuts" user "Board Geometry/Outline")
		(27 "Margin" user)
		(31 "F.CrtYd" user "Package Geometry/Place Bound Top")
		(29 "B.CrtYd" user "Package Geometry/Place Bound Bottom")
		(35 "F.Fab" user "Ref Des/Assembly Top")
		(33 "B.Fab" user "Ref Des/Assembly Bottom")
	)
	(footprint ""
		(layer "F.Cu")
		(at 114.826034 -66.672206 90)
		(property "Reference" "R806"
			(at 0 0 90)
			(layer "F.SilkS")
			(hide yes)
			(effects
				(font
					(size 1.27 1.27)
				)
			)
		)
		(property "Value" ""
			(at 0 0 90)
			(layer "F.Fab")
			(effects
				(font
					(size 1.27 1.27)
				)
			)
		)
		(duplicate_pad_numbers_are_jumpers no)
		(fp_line
			(start 0.7874 -0.4064)
			(end 0.7874 0.4064)
			(stroke
				(width 0.1524)
				(type default)
			)
			(layer "F.SilkS")
		)
		(fp_line
			(start -0.7874 -0.4064)
			(end 0.7874 -0.4064)
			(stroke
				(width 0.1524)
				(type default)
			)
			(layer "F.SilkS")
		)
		(fp_line
			(start 0.7874 0.4064)
			(end -0.7874 0.4064)
			(stroke
				(width 0.1524)
				(type default)
			)
			(layer "F.SilkS")
		)
		(fp_line
			(start -0.7874 0.4064)
			(end -0.7874 -0.4064)
			(stroke
				(width 0.1524)
				(type default)
			)
			(layer "F.SilkS")
		)
		(fp_line
			(start -0.12065 -0.305054)
			(end -0.12065 -0.2794)
			(stroke
				(width 0.1)
				(type default)
			)
			(layer "F.Fab")
		)
		(fp_line
			(start -0.67945 -0.305054)
			(end -0.12065 -0.305054)
			(stroke
				(width 0.1)
				(type default)
			)
			(layer "F.Fab")
		)
		(fp_line
			(start 0.67945 -0.3048)
			(end 0.67945 0.3048)
			(stroke
				(width 0.1)
				(type default)
			)
			(layer "F.Fab")
		)
		(fp_line
			(start 0.12065 -0.3048)
			(end 0.67945 -0.3048)
			(stroke
				(width 0.1)
				(type default)
			)
			(layer "F.Fab")
		)
		(fp_line
			(start 0.12065 -0.2794)
			(end 0.12065 -0.3048)
			(stroke
				(width 0.1)
				(type default)
			)
			(layer "F.Fab")
		)
		(fp_line
			(start -0.12065 -0.2794)
			(end 0.12065 -0.2794)
			(stroke
				(width 0.1)
				(type default)
			)
			(layer "F.Fab")
		)
		(fp_line
			(start 0.120396 0.2794)
			(end -0.12065 0.2794)
			(stroke
				(width 0.1)
				(type default)
			)
			(layer "F.Fab")
		)
		(fp_line
			(start -0.12065 0.2794)
			(end -0.12065 0.3048)
			(stroke
				(width 0.1)
				(type default)
			)
			(layer "F.Fab")
		)
		(fp_line
			(start 0.67945 0.3048)
			(end 0.120396 0.3048)
			(stroke
				(width 0.1)
				(type default)
			)
			(layer "F.Fab")
		)
		(fp_line
			(start 0.120396 0.3048)
			(end 0.120396 0.2794)
			(stroke
				(width 0.1)
				(type default)
			)
			(layer "F.Fab")
		)
		(fp_line
			(start -0.12065 0.3048)
			(end -0.67945 0.3048)
			(stroke
				(width 0.1)
				(type default)
			)
			(layer "F.Fab")
		)
		(fp_line
			(start -0.67945 0.3048)
			(end -0.67945 -0.305054)
			(stroke
				(width 0.1)
				(type default)
			)
			(layer "F.Fab")
		)
		(pad "1" smd circle
			(at -0.40005 0 90)
			(size 0 0)
			(layers "F.Cu" "F.Mask" "F.Paste")
			(net "JTAG_PLD_TCK_R")
		)
		(pad "2" smd circle
			(at 0.40005 0 90)
			(size 0 0)
			(layers "F.Cu" "F.Mask" "F.Paste")
			(net "JTAG_BMC_PLD_TCK")
		)
	)
	(footprint ""
		(layer "F.Cu")
		(at 185.799222 -22.097492 180)
		(property "Reference" "PR4002"
			(at 0 0 180)
			(layer "F.SilkS")
			(hide yes)
			(effects
				(font
					(size 1.27 1.27)
				)
			)
		)
		(property "Value" ""
			(at 0 0 180)
			(layer "F.Fab")
			(effects
				(font
					(size 1.27 1.27)
				)
			)
		)
		(duplicate_pad_numbers_are_jumpers no)
		(fp_line
			(start 0.7874 0.4064)
			(end -0.7874 0.4064)
			(stroke
				(width 0.1524)
				(type default)
			)
			(layer "F.SilkS")
		)
		(fp_line
			(start 0.7874 -0.4064)
			(end 0.7874 0.4064)
			(stroke
				(width 0.1524)
				(type default)
			)
			(layer "F.SilkS")
		)
		(fp_line
			(start -0.7874 0.4064)
			(end -0.7874 -0.4064)
			(stroke
				(width 0.1524)
				(type default)
			)
			(layer "F.SilkS")
		)
		(fp_line
			(start -0.7874 -0.4064)
			(end 0.7874 -0.4064)
			(stroke
				(width 0.1524)
				(type default)
			)
			(layer "F.SilkS")
		)
		(fp_line
			(start 0.67945 0.3048)
			(end 0.120396 0.3048)
			(stroke
				(width 0.1)
				(type default)
			)
			(layer "F.Fab")
		)
		(fp_line
			(start 0.67945 -0.3048)
			(end 0.67945 0.3048)
			(stroke
				(width 0.1)
				(type default)
			)
			(layer "F.Fab")
		)
		(fp_line
			(start 0.12065 -0.2794)
			(end 0.12065 -0.3048)
			(stroke
				(width 0.1)
				(type default)
			)
			(layer "F.Fab")
		)
		(fp_line
			(start 0.12065 -0.3048)
			(end 0.67945 -0.3048)
			(stroke
				(width 0.1)
				(type default)
			)
			(layer "F.Fab")
		)
		(fp_line
			(start 0.120396 0.3048)
			(end 0.120396 0.2794)
			(stroke
				(width 0.1)
				(type default)
			)
			(layer "F.Fab")
		)
		(fp_line
			(start 0.120396 0.2794)
			(end -0.12065 0.2794)
			(stroke
				(width 0.1)
				(type default)
			)
			(layer "F.Fab")
		)
		(fp_line
			(start -0.12065 0.3048)
			(end -0.67945 0.3048)
			(stroke
				(width 0.1)
				(type default)
			)
			(layer "F.Fab")
		)
		(fp_line
			(start -0.12065 0.2794)
			(end -0.12065 0.3048)
			(stroke
				(width 0.1)
				(type default)
			)
			(layer "F.Fab")
		)
		(fp_line
			(start -0.12065 -0.2794)
			(end 0.12065 -0.2794)
			(stroke
				(width 0.1)
				(type default)
			)
			(layer "F.Fab")
		)
		(fp_line
			(start -0.12065 -0.305054)
			(end -0.12065 -0.2794)
			(stroke
				(width 0.1)
				(type default)
			)
			(layer "F.Fab")
		)
		(fp_line
			(start -0.67945 0.3048)
			(end -0.67945 -0.305054)
			(stroke
				(width 0.1)
				(type default)
			)
			(layer "F.Fab")
		)
		(fp_line
			(start -0.67945 -0.305054)
			(end -0.12065 -0.305054)
			(stroke
				(width 0.1)
				(type default)
			)
			(layer "F.Fab")
		)
		(pad "1" smd circle
			(at -0.40005 0 180)
			(size 0 0)
			(layers "F.Cu" "F.Mask" "F.Paste")
			(net "P12V_SCM_OV")
		)
		(pad "2" smd circle
			(at 0.40005 0 180)
			(size 0 0)
			(layers "F.Cu" "F.Mask" "F.Paste")
			(net "GND")
		)
	)
)
